# T6G (Grand Teton) — schematic netlist excerpt (pin names and nets, part order shuffled) for the footprints in the layout excerpt that follows; sources: Cadence DE-HDL packaged netlist, KiCad conversion of 04192023_DAF0TMB3IC0_F0TG_MB_C_brd_V02_OCP.brd

C2424  Q_CAP  22UF 4V 20% X6S  pkg C0402  page 74 : A = PVDDCR_SOC_P1 ; B = GND
R6035  Q_RES  4.7K 5% EMPTY  pkg 0402LF  page 150 : A = SCM_ROT_CPU_RST_R_N ; B = GND
R1511  Q_RES  4.7K 5% EMPTY  pkg 0201LF  page 353 : A = P1V8_CPU1_RT_1D ; B = JTAG_TMS_RT_CPU1_P3

(kicad_pcb
	(version 20260206)
	(generator "pcbnew")
	(generator_version "10.0")
	(general
		(thickness 1.6)
		(legacy_teardrops no)
	)
	(paper "A4")
	(title_block
		(title "04192023_DAF0TMB3IC0_F0TG_MB_C_brd_V02_OCP.brd")
		(comment 1 "Grand Teton / footprints 8257-8259 of 8354")
	)
	(layers
		(0 "F.Cu" signal "TOP")
		(4 "In1.Cu" signal "GND")
		(6 "In2.Cu" signal "IN1")
		(8 "In3.Cu" signal "GND1")
		(10 "In4.Cu" signal "IN2")
		(12 "In5.Cu" signal "GND2")
		(14 "In6.Cu" signal "IN3")
		(16 "In7.Cu" signal "GND3")
		(18 "In8.Cu" signal "VCC")
		(20 "In9.Cu" signal "VCC1")
		(22 "In10.Cu" signal "GND4")
		(24 "In11.Cu" signal "IN4")
		(26 "In12.Cu" signal "GND5")
		(28 "In13.Cu" signal "IN5")
		(30 "In14.Cu" signal "GND6")
		(32 "In15.Cu" signal "IN6")
		(34 "In16.Cu" signal "GND7")
		(2 "B.Cu" signal "BOTTOM")
		(9 "F.Adhes" user "F.Adhesive")
		(11 "B.Adhes" user "B.Adhesive")
		(13 "F.Paste" user "Package Geometry/Pastemask Top")
		(15 "B.Paste" user "Package Geometry/Pastemask Bottom")
		(5 "F.SilkS" user "Ref Des/Silkscreen Top")
		(7 "B.SilkS" user "Ref Des/Silkscreen Bottom")
		(1 "F.Mask" user "Board Geometry/Soldermask Top")
		(3 "B.Mask" user "Board Geometry/Soldermask Bottom")
		(17 "Dwgs.User" user "User.Drawings")
		(19 "Cmts.User" user "User.Comments")
		(21 "Eco1.User" user "User.Eco1")
		(23 "Eco2.User" user "User.Eco2")
		(25 "Edge.Cuts" user "Board Geometry/Outline")
		(27 "Margin" user)
		(31 "F.CrtYd" user "Package Geometry/Place Bound Top")
		(29 "B.CrtYd" user "Package Geometry/Place Bound Bottom")
		(35 "F.Fab" user "Ref Des/Assembly Top")
		(33 "B.Fab" user "Ref Des/Assembly Bottom")
	)
	(footprint ""
		(layer "B.Cu")
		(at 137.851642 -9.036304 -90)
		(property "Reference" "R6035"
			(at 0 0 90)
			(layer "B.SilkS")
			(hide yes)
			(effects
				(font
					(size 1.27 1.27)
				)
				(justify mirror)
			)
		)
		(property "Value" ""
			(at 0 0 90)
			(layer "B.Fab")
			(effects
				(font
					(size 1.27 1.27)
				)
				(justify mirror)
			)
		)
		(duplicate_pad_numbers_are_jumpers no)
		(fp_line
			(start -0.7874 0.4064)
			(end 0.7874 0.4064)
			(stroke
				(width 0.1524)
				(type default)
			)
			(layer "B.SilkS")
		)
		(fp_line
			(start 0.7874 0.4064)
			(end 0.7874 -0.4064)
			(stroke
				(width 0.1524)
				(type default)
			)
			(layer "B.SilkS")
		)
		(fp_line
			(start -0.7874 -0.4064)
			(end -0.7874 0.4064)
			(stroke
				(width 0.1524)
				(type default)
			)
			(layer "B.SilkS")
		)
		(fp_line
			(start 0.7874 -0.4064)
			(end -0.7874 -0.4064)
			(stroke
				(width 0.1524)
				(type default)
			)
			(layer "B.SilkS")
		)
		(fp_line
			(start -0.67945 0.3048)
			(end -0.120396 0.3048)
			(stroke
				(width 0.1)
				(type default)
			)
			(layer "B.Fab")
		)
		(fp_line
			(start -0.120396 0.3048)
			(end -0.120396 0.2794)
			(stroke
				(width 0.1)
				(type default)
			)
			(layer "B.Fab")
		)
		(fp_line
			(start 0.12065 0.3048)
			(end 0.67945 0.3048)
			(stroke
				(width 0.1)
				(type default)
			)
			(layer "B.Fab")
		)
		(fp_line
			(start 0.67945 0.3048)
			(end 0.67945 -0.305054)
			(stroke
				(width 0.1)
				(type default)
			)
			(layer "B.Fab")
		)
		(fp_line
			(start -0.120396 0.2794)
			(end 0.12065 0.2794)
			(stroke
				(width 0.1)
				(type default)
			)
			(layer "B.Fab")
		)
		(fp_line
			(start 0.12065 0.2794)
			(end 0.12065 0.3048)
			(stroke
				(width 0.1)
				(type default)
			)
			(layer "B.Fab")
		)
		(fp_line
			(start -0.12065 -0.2794)
			(end -0.12065 -0.3048)
			(stroke
				(width 0.1)
				(type default)
			)
			(layer "B.Fab")
		)
		(fp_line
			(start 0.12065 -0.2794)
			(end -0.12065 -0.2794)
			(stroke
				(width 0.1)
				(type default)
			)
			(layer "B.Fab")
		)
		(fp_line
			(start -0.67945 -0.3048)
			(end -0.67945 0.3048)
			(stroke
				(width 0.1)
				(type default)
			)
			(layer "B.Fab")
		)
		(fp_line
			(start -0.12065 -0.3048)
			(end -0.67945 -0.3048)
			(stroke
				(width 0.1)
				(type default)
			)
			(layer "B.Fab")
		)
		(fp_line
			(start 0.12065 -0.305054)
			(end 0.12065 -0.2794)
			(stroke
				(width 0.1)
				(type default)
			)
			(layer "B.Fab")
		)
		(fp_line
			(start 0.67945 -0.305054)
			(end 0.12065 -0.305054)
			(stroke
				(width 0.1)
				(type default)
			)
			(layer "B.Fab")
		)
		(pad "1" smd circle
			(at 0.40005 0 90)
			(size 0 0)
			(layers "B.Cu" "B.Mask" "B.Paste")
			(net "SCM_ROT_CPU_RST_R_N")
		)
		(pad "2" smd circle
			(at -0.40005 0 90)
			(size 0 0)
			(layers "B.Cu" "B.Mask" "B.Paste")
			(net "GND")
		)
	)
	(footprint ""
		(layer "B.Cu")
		(at 117.895624 -255.555242)
		(property "Reference" "C2424"
			(at 0 0 0)
			(layer "B.SilkS")
			(hide yes)
			(effects
				(font
					(size 1.27 1.27)
				)
				(justify mirror)
			)
		)
		(property "Value" ""
			(at 0 0 0)
			(layer "B.Fab")
			(effects
				(font
					(size 1.27 1.27)
				)
				(justify mirror)
			)
		)
		(duplicate_pad_numbers_are_jumpers no)
		(fp_line
			(start -0.7874 -0.4064)
			(end -0.7874 0.4064)
			(stroke
				(width 0.1524)
				(type default)
			)
			(layer "B.SilkS")
		)
		(fp_line
			(start -0.7874 0.4064)
			(end 0.7874 0.4064)
			(stroke
				(width 0.1524)
				(type default)
			)
			(layer "B.SilkS")
		)
		(fp_line
			(start 0.7874 -0.4064)
			(end -0.7874 -0.4064)
			(stroke
				(width 0.1524)
				(type default)
			)
			(layer "B.SilkS")
		)
		(fp_line
			(start 0.7874 0.4064)
			(end 0.7874 -0.4064)
			(stroke
				(width 0.1524)
				(type default)
			)
			(layer "B.SilkS")
		)
		(fp_line
			(start -0.67945 -0.3048)
			(end -0.67945 0.3048)
			(stroke
				(width 0.1)
				(type default)
			)
			(layer "B.Fab")
		)
		(fp_line
			(start -0.67945 0.3048)
			(end -0.120396 0.3048)
			(stroke
				(width 0.1)
				(type default)
			)
			(layer "B.Fab")
		)
		(fp_line
			(start -0.12065 -0.3048)
			(end -0.67945 -0.3048)
			(stroke
				(width 0.1)
				(type default)
			)
			(layer "B.Fab")
		)
		(fp_line
			(start -0.12065 -0.2794)
			(end -0.12065 -0.3048)
			(stroke
				(width 0.1)
				(type default)
			)
			(layer "B.Fab")
		)
		(fp_line
			(start -0.120396 0.2794)
			(end 0.12065 0.2794)
			(stroke
				(width 0.1)
				(type default)
			)
			(layer "B.Fab")
		)
		(fp_line
			(start -0.120396 0.3048)
			(end -0.120396 0.2794)
			(stroke
				(width 0.1)
				(type default)
			)
			(layer "B.Fab")
		)
		(fp_line
			(start 0.12065 -0.305054)
			(end 0.12065 -0.2794)
			(stroke
				(width 0.1)
				(type default)
			)
			(layer "B.Fab")
		)
		(fp_line
			(start 0.12065 -0.2794)
			(end -0.12065 -0.2794)
			(stroke
				(width 0.1)
				(type default)
			)
			(layer "B.Fab")
		)
		(fp_line
			(start 0.12065 0.2794)
			(end 0.12065 0.3048)
			(stroke
				(width 0.1)
				(type default)
			)
			(layer "B.Fab")
		)
		(fp_line
			(start 0.12065 0.3048)
			(end 0.67945 0.3048)
			(stroke
				(width 0.1)
				(type default)
			)
			(layer "B.Fab")
		)
		(fp_line
			(start 0.67945 -0.305054)
			(end 0.12065 -0.305054)
			(stroke
				(width 0.1)
				(type default)
			)
			(layer "B.Fab")
		)
		(fp_line
			(start 0.67945 0.3048)
			(end 0.67945 -0.305054)
			(stroke
				(width 0.1)
				(type default)
			)
			(layer "B.Fab")
		)
		(pad "1" smd circle
			(at 0.40005 0 180)
			(size 0 0)
			(layers "B.Cu" "B.Mask" "B.Paste")
			(net "PVDDCR_SOC_P1")
		)
		(pad "2" smd circle
			(at -0.40005 0 180)
			(size 0 0)
			(layers "B.Cu" "B.Mask" "B.Paste")
			(net "GND")
		)
	)
	(footprint ""
		(layer "B.Cu")
		(at 163.5252 -424.60037 -90)
		(property "Reference" "R1511"
			(at 0 0 90)
			(layer "B.SilkS")
			(hide yes)
			(effects
				(font
					(size 1.27 1.27)
				)
				(justify mirror)
			)
		)
		(property "Value" ""
			(at 0 0 90)
			(layer "B.Fab")
			(effects
				(font
					(size 1.27 1.27)
				)
				(justify mirror)
			)
		)
		(duplicate_pad_numbers_are_jumpers no)
		(fp_line
			(start -0.32512 0.175006)
			(end 0.32512 0.175006)
			(stroke
				(width 0.1)
				(type default)
			)
			(layer "B.Fab")
		)
		(fp_line
			(start 0.32512 0.175006)
			(end 0.32512 -0.175006)
			(stroke
				(width 0.1)
				(type default)
			)
			(layer "B.Fab")
		)
		(fp_line
			(start -0.32512 -0.175006)
			(end -0.32512 0.175006)
			(stroke
				(width 0.1)
				(type default)
			)
			(layer "B.Fab")
		)
		(fp_line
			(start 0.32512 -0.175006)
			(end -0.32512 -0.175006)
			(stroke
				(width 0.1)
				(type default)
			)
			(layer "B.Fab")
		)
		(pad "1" smd rect
			(at 0.2667 0 90)
			(size 0.3048 0.381)
			(layers "B.Cu" "B.Mask" "B.Paste")
			(net "P1V8_CPU1_RT_1D")
		)
		(pad "2" smd rect
			(at -0.2667 0 270)
			(size 0.3048 0.381)
			(layers "B.Cu" "B.Mask" "B.Paste")
			(net "JTAG_TMS_RT_CPU1_P3")
		)
	)
)
